FILE_TYPE = CONNECTIVITY;
{Allegro Design Entry HDL 16.6-p007 (v16-6-112F) 10/10/2012}
"PAGE_NUMBER" = 72;
0"NC";
1"PVDDQ_GHJ\g";
2"PVDDQ_KLM\g";
3"PVCCIO_CPU1\g";
4"PVCCIO_CPU1\g";
5"PVSA_CPU1\g";
6"GND\g";
7"PVCCMCP_CPU1\g";
8"PVCCIOMCP_CPU1\g";
9"PVPP_GHJ\g";
10"P1V8_MCP_CPU1\g";
11"P3V3_STBY\g";
%"PVDDQ_GHJ"
"1","(-7325,4250)","0","mstr_symbols","I14";
;
VOLTAGE"1.2V"
CDS_LIB"mstr_symbols"
BODY_TYPE"PLUMBING"
HDL_POWER"PVDDQ_GHJ";
"G\NAC"1;
%"PVDDQ_KLM"
"1","(-5050,4250)","0","mstr_symbols","I15";
;
VOLTAGE"1.2V"
CDS_LIB"mstr_symbols"
BODY_TYPE"PLUMBING"
HDL_POWER"PVDDQ_KLM";
"G\NAC"2;
%"PVCCIO_CPU1"
"1","(-3850,4850)","0","mstr_symbols","I17";
;
VOLTAGE"1.1V"
CDS_LIB"mstr_symbols"
BODY_TYPE"PLUMBING"
HDL_POWER"PVCCIO_CPU1";
"G\NAC"3;
%"PVCCIO_CPU1"
"1","(-1200,1050)","0","mstr_symbols","I18";
;
HDL_POWER"PVCCIO_CPU1"
BODY_TYPE"PLUMBING"
CDS_LIB"mstr_symbols"
VOLTAGE"1.1V";
"G\NAC"4;
%"PVSA_CPU1"
"1","(-1600,4825)","0","mstr_symbols","I22";
;
VOLTAGE"1.1V"
CDS_LIB"mstr_symbols"
BODY_TYPE"PLUMBING"
HDL_POWER"PVSA_CPU1";
"G\NAC"5;
%"GND"
"1","(-700,950)","0","mstr_symbols","I23";
;
VOLTAGE"0.0V"
CDS_LIB"mstr_symbols"
SIZE"1B"
BODY_TYPE"PLUMBING"
HDL_POWER"GND";
"A\NAC"6;
%"CAP"
"1","(-700,1175)","0","mstr_discrete","I25";
;
LOCATION"C3D3"
VALUE"10UF"
VOLTAGE"4V"
TOLERANCE"20%"
MATERIAL"X6S"
PART_NUMBER"E15431-001"
PACK_TYPE"0603LF"
GROUP"PWR_MCP_CAP"
BOM_COST"PROC_SOCKET"
CDS_LIB"mstr_discrete"
CDS_SEC"1"
$SEC"1"
CDS_LOCATION"C3D3"
ROOM"CPU1";
"A"
$PN"1"10;
"B"
$PN"2"6;
%"VCC_CORE"
"1","(-1250,3300)","0","mstr_symbols","I28";
;
HDL_POWER"PVCCMCP_CPU1"
CDS_LIB"mstr_symbols";
"A"7;
%"VCC_CORE"
"1","(-1250,2575)","0","mstr_symbols","I29";
;
HDL_POWER"PVCCIOMCP_CPU1"
VOLTAGE"+0.95V"
CDS_LIB"mstr_symbols";
"A"8;
%"SKX_EXT_B"
"20","(-6200,2550)","0","chpset_lib","I32";
;
CDS_SEC"20"
LOCATION"U2D1"
PART_NUMBER"TBD"
MATERIAL"IC"
PACK_TYPE"BGA1"
SEC_TYPE"BGA1"
CDS_LIB"chpset_lib"
SEC"20"
CDS_LOCATION"U2D1";
"VCCD345<0>"
$PN"EF59"2;
"VCCD345<1>"
$PN"EF53"2;
"VCCD345<2>"
$PN"EF49"2;
"VCCD345<3>"
$PN"EC62"2;
"VCCD345<4>"
$PN"EC60"2;
"VCCD345<5>"
$PN"EC58"2;
"VCCD345<6>"
$PN"EC56"2;
"VCCD345<7>"
$PN"EC54"2;
"VCCD345<8>"
$PN"EC52"2;
"VCCD345<9>"
$PN"EC50"2;
"VCCD345<10>"
$PN"EC48"2;
"VCCD345<11>"
$PN"EC46"2;
"VCCD345<12>"
$PN"DU64"2;
"VCCD345<13>"
$PN"DU62"2;
"VCCD345<14>"
$PN"DU60"2;
"VCCD345<15>"
$PN"DU58"2;
"VCCD345<16>"
$PN"DU56"2;
"VCCD345<17>"
$PN"DU54"2;
"VCCD345<18>"
$PN"DU52"2;
"VCCD345<19>"
$PN"DU50"2;
"VCCD345<20>"
$PN"DU48"2;
"VCCD345<21>"
$PN"DU46"2;
"VCCD345<22>"
$PN"DL62"2;
"VCCD345<23>"
$PN"DL60"2;
"VCCD345<24>"
$PN"DL58"2;
"VCCD345<25>"
$PN"DL56"2;
"VCCD345<26>"
$PN"DL54"2;
"VCCD345<27>"
$PN"DL52"2;
"VCCD345<28>"
$PN"DL50"2;
"VCCD345<29>"
$PN"DL48"2;
"VCCD345<30>"
$PN"DL46"2;
"VCCD345<31>"
$PN"DJ64"2;
"VCCD345<32>"
$PN"DH63"2;
"VCCD345<33>"
$PN"DH61"2;
"VCCD345<34>"
$PN"DH59"2;
"VCCD345<35>"
$PN"DH57"2;
"VCCD345<36>"
$PN"DH55"2;
"VCCD345<37>"
$PN"DH53"2;
"VCCD345<38>"
$PN"DH51"2;
"VCCD345<39>"
$PN"DH49"2;
"VCCD345<40>"
$PN"DH47"2;
"VCCD345<41>"
$PN"DH45"2;
"VCCD345<42>"
$PN"DD45"2;
"VCCD345<43>"
$PN"DB63"2;
"VCCD345<44>"
$PN"DB61"2;
"VCCD345<45>"
$PN"DB59"2;
"VCCD345<46>"
$PN"DB57"2;
"VCCD345<47>"
$PN"DB55"2;
"VCCD345<48>"
$PN"DB53"2;
"VCCD345<49>"
$PN"EF45"2;
"VCCD345<50>"
$PN"EE44"2;
"VCCD012<0>"
$PN"B49"1;
"VCCD012<1>"
$PN"B53"1;
"VCCD012<2>"
$PN"B59"1;
"VCCD012<3>"
$PN"E46"1;
"VCCD012<4>"
$PN"E48"1;
"VCCD012<5>"
$PN"E50"1;
"VCCD012<6>"
$PN"E52"1;
"VCCD012<7>"
$PN"E54"1;
"VCCD012<8>"
$PN"E56"1;
"VCCD012<9>"
$PN"E58"1;
"VCCD012<10>"
$PN"E60"1;
"VCCD012<11>"
$PN"E62"1;
"VCCD012<12>"
$PN"E64"1;
"VCCD012<13>"
$PN"L46"1;
"VCCD012<14>"
$PN"L48"1;
"VCCD012<15>"
$PN"L50"1;
"VCCD012<16>"
$PN"L52"1;
"VCCD012<17>"
$PN"L54"1;
"VCCD012<18>"
$PN"L56"1;
"VCCD012<19>"
$PN"L58"1;
"VCCD012<20>"
$PN"L60"1;
"VCCD012<21>"
$PN"L62"1;
"VCCD012<22>"
$PN"N64"1;
"VCCD012<23>"
$PN"U46"1;
"VCCD012<24>"
$PN"U48"1;
"VCCD012<25>"
$PN"U50"1;
"VCCD012<26>"
$PN"U52"1;
"VCCD012<27>"
$PN"U54"1;
"VCCD012<28>"
$PN"U56"1;
"VCCD012<29>"
$PN"U58"1;
"VCCD012<30>"
$PN"U60"1;
"VCCD012<31>"
$PN"U62"1;
"VCCD012<32>"
$PN"W64"1;
"VCCD012<33>"
$PN"Y45"1;
"VCCD012<34>"
$PN"Y47"1;
"VCCD012<35>"
$PN"Y49"1;
"VCCD012<36>"
$PN"Y51"1;
"VCCD012<37>"
$PN"Y53"1;
"VCCD012<38>"
$PN"Y55"1;
"VCCD012<39>"
$PN"Y57"1;
"VCCD012<40>"
$PN"Y59"1;
"VCCD012<41>"
$PN"Y61"1;
"VCCD012<42>"
$PN"Y63"1;
"VCCD012<43>"
$PN"AD45"1;
"VCCD012<44>"
$PN"AF55"1;
"VCCD012<45>"
$PN"AF57"1;
"VCCD012<46>"
$PN"AF59"1;
"VCCD012<47>"
$PN"AF61"1;
"VCCD012<48>"
$PN"AF63"1;
"VCCD012<49>"
$PN"D45"1;
"VCCD012<50>"
$PN"C46"1;
"VCCD012<51>"
$PN"B47"1;
%"SKX_EXT_B"
"21","(-2700,2575)","0","chpset_lib","I33";
;
CDS_SEC"21"
LOCATION"U2D1"
PART_NUMBER"TBD"
MATERIAL"IC"
PACK_TYPE"BGA1"
SEC_TYPE"BGA1"
CDS_LIB"chpset_lib"
SEC"21"
CDS_LOCATION"U2D1";
"VCCSA<0>"
$PN"CJ66"5;
"VCCSA<1>"
$PN"CJ64"5;
"VCCSA<2>"
$PN"CH75"5;
"VCCSA<3>"
$PN"CH65"5;
"VCCSA<4>"
$PN"CG74"5;
"VCCSA<5>"
$PN"CG66"5;
"VCCSA<6>"
$PN"CG64"5;
"VCCSA<7>"
$PN"CF75"5;
"VCCSA<8>"
$PN"CF73"5;
"VCCSA<9>"
$PN"CF67"5;
"VCCSA<10>"
$PN"CF65"5;
"VCCSA<11>"
$PN"CE74"5;
"VCCSA<12>"
$PN"CE72"5;
"VCCSA<13>"
$PN"CE68"5;
"VCCSA<14>"
$PN"CE66"5;
"VCCSA<15>"
$PN"CE64"5;
"VCCSA<16>"
$PN"CD71"5;
"VCCSA<17>"
$PN"CD69"5;
"VCCSA<18>"
$PN"CD67"5;
"VCCSA<19>"
$PN"CD65"5;
"VCCSA<20>"
$PN"CC70"5;
"VCCSA<21>"
$PN"CC68"5;
"VCCSA<22>"
$PN"CC66"5;
"VCCSA<23>"
$PN"CB69"5;
"VCCSA<24>"
$PN"CB67"5;
"VCCSA<25>"
$PN"CB65"5;
"VCCIO<20>"
$PN"CM15"4;
"VCCIO<21>"
$PN"CL12"4;
"VCCIO<22>"
$PN"CK5"4;
"VCCIO<23>"
$PN"CV7"4;
"VCCIO<24>"
$PN"CH9"4;
"VCCIO<25>"
$PN"D7"4;
"VCCIO<26>"
$PN"CE18"4;
"VCCIO<27>"
$PN"CD9"4;
"VCCIO<28>"
$PN"CB17"4;
"VCCIO<29>"
$PN"CB13"4;
"VCCIO<30>"
$PN"BP25"3;
"VCCIO<31>"
$PN"BJ24"3;
"VCCIO<32>"
$PN"BF23"3;
"VCCIO<33>"
$PN"DA14"3;
"VCCIO<34>"
$PN"BB5"3;
"VCCIO<35>"
$PN"BA24"3;
"VCCIO<36>"
$PN"AY11"3;
"VCCIO<37>"
$PN"AW6"3;
"VCCIO<38>"
$PN"AT11"3;
"VCCIO<39>"
$PN"DD7"3;
"VCCIO<40>"
$PN"AN10"3;
"VCCIO<41>"
$PN"DF13"3;
"VCCIO<42>"
$PN"AH9"3;
"VCCIO<43>"
$PN"AC4"3;
"VCCIO<44>"
$PN"AC20"3;
"VCCIO<45>"
$PN"AA10"3;
"VCCIO<46>"
$PN"W6"3;
"VCCIO<47>"
$PN"W4"3;
"VCCIO<48>"
$PN"DF21"3;
"VCCIO<49>"
$PN"U14"3;
"VCCIO<50>"
$PN"T3"3;
"VCCIO<51>"
$PN"P5"3;
"VCCIO<52>"
$PN"M21"3;
"VCCIO<53>"
$PN"M11"3;
"VCCIO<54>"
$PN"DG8"3;
"VCCIO<55>"
$PN"DH7"3;
"VCCIO<56>"
$PN"L16"3;
"VCCIO<57>"
$PN"L14"3;
"VCCIO<58>"
$PN"J10"3;
"VCCIO<59>"
$PN"H13"3;
"VCCIO<60>"
$PN"DJ16"3;
"VCCIO<61>"
$PN"DM17"3;
"VCCIO<62>"
$PN"DN8"3;
"VCCIO<63>"
$PN"DP19"3;
"VCCIO<64>"
$PN"DR10"3;
"VCCIO<65>"
$PN"DR2"3;
"VCCIO<66>"
$PN"DU20"3;
"VCCIO<67>"
$PN"EA12"3;
"VCCIO<68>"
$PN"EB15"3;
"VCCIO<69>"
$PN"J2"3;
"VCCIO<70>"
$PN"K15"3;
"VCCIO<71>"
$PN"M7"3;
"VCCIO<72>"
$PN"M9"3;
"VCCIO<73>"
$PN"N18"3;
"VCCIO<74>"
$PN"W10"3;
"VCCIO<75>"
$PN"BC26"3;
"VCCIO<76>"
$PN"BB27"3;
"VCCIO<77>"
$PN"BA26"3;
"VCCIO<78>"
$PN"AY27"3;
"VCCIO<79>"
$PN"AW26"3;
"VCCIO<80>"
$PN"AV27"3;
"VCCIO<81>"
$PN"CF27"3;
"VCCIO<82>"
$PN"CD27"3;
"VCCIO<83>"
$PN"CC26"3;
"VCCIO<84>"
$PN"CJ28"3;
"VCCIO<85>"
$PN"CH27"3;
"VCCIO<86>"
$PN"BM27"3;
"VCCIO<87>"
$PN"BL26"3;
"VCCIO<88>"
$PN"BK27"3;
"VCCIO<89>"
$PN"BK25"3;
"VCCIO<90>"
$PN"BJ26"3;
"VCCIO<91>"
$PN"BH27"3;
"VCCIO<92>"
$PN"BH25"3;
"VCCIO<93>"
$PN"BG26"3;
"VCCIO<94>"
$PN"BF27"3;
"VCCIO<95>"
$PN"AE36"3;
"VCCIO<96>"
$PN"AD37"3;
"VCCIO<97>"
$PN"AC36"3;
"VCCIO<98>"
$PN"AF35"3;
"VCCIO<99>"
$PN"AD35"3;
"VCCIO<100>"
$PN"AE34"3;
"VCCIO<101>"
$PN"AG34"3;
"VCCIO<102>"
$PN"AM29"3;
"VCCIO<103>"
$PN"AL28"3;
"VCCIO<104>"
$PN"AR28"3;
"VCC33"
$PN"CY55"11;
"CD_VPP<0>"
$PN"B11"9;
"CD_VPP<1>"
$PN"A12"9;
"CD_VPP<2>"
$PN"A10"9;
"CD_VPP<3>"
$PN"A8"9;
"CD_VCC_CORE<0>"
$PN"BL14"7;
"CD_VCC_CORE<1>"
$PN"BK15"7;
"CD_VCC_CORE<2>"
$PN"BK13"7;
"CD_VCC_CORE<3>"
$PN"BJ14"7;
"CD_VCC_CORE<4>"
$PN"BJ12"7;
"CD_VCC_CORE<5>"
$PN"BH13"7;
"CD_VCC_CORE<6>"
$PN"BG14"7;
"CD_VCC_CORE<7>"
$PN"BG12"7;
"CD_VCC_CORE<8>"
$PN"BF13"7;
"CD_VCC_CORE<9>"
$PN"BF11"7;
"CD_VCC_CORE<10>"
$PN"BE14"7;
"CD_VCC_CORE<11>"
$PN"BE12"7;
"CD_VCC_CORE<12>"
$PN"BD13"7;
"CD_VCCP<0>"
$PN"BV15"8;
"CD_VCCP<1>"
$PN"BV13"8;
"CD_VCCP<2>"
$PN"BV11"8;
"CD_VCCP<3>"
$PN"BU14"8;
"CD_VCCP<4>"
$PN"BU12"8;
"CD_VCCP<5>"
$PN"BT15"8;
"CD_VCCP<6>"
$PN"BT13"8;
"CD_VCCP<7>"
$PN"BT11"8;
"CD_VCCP<8>"
$PN"BR14"8;
"CD_VCCP<9>"
$PN"BR12"8;
"CD_VCCP<10>"
$PN"BP15"8;
"CD_VCCP<11>"
$PN"BP13"8;
"CD_VCCP<12>"
$PN"BP11"8;
"CD_VCCP<13>"
$PN"BN14"8;
"CD_VCCP<14>"
$PN"BN12"8;
"CD_VCCP<15>"
$PN"BM11"8;
"CD_VCCIN<0>"
$PN"BT27"10;
"CD_VCCIN<1>"
$PN"BU26"10;
"CD_VCCIN<2>"
$PN"BV27"10;
"CD_VCCIN<3>"
$PN"BY27"10;
%"PVPP_GHJ"
"1","(-1425,1925)","0","mstr_symbols","I38";
;
VOLTAGE"2.5V"
BOM_COST"PVPP_KLM_VR"
CDS_LIB"mstr_symbols"
BODY_TYPE"PLUMBING"
ROOM"PVPP_KLM_VR"
HDL_POWER"PVPP_GHJ";
"G\NAC"9;
%"VCC_CORE"
"1","(-700,1425)","0","mstr_symbols","I39";
;
HDL_POWER"P1V8_MCP_CPU1"
CDS_LIB"mstr_symbols"
VOLTAGE"1.8";
"A"10;
%"P3V3_STBY"
"1","(-1200,1225)","0","mstr_symbols","I40";
;
VOLTAGE"3.3V"
SIZE"1B"
CDS_LIB"mstr_symbols"
BODY_TYPE"PLUMBING"
HDL_POWER"P3V3_STBY";
"G\NAC"11;
END.
